# BASEBOARD_FAB2 (Tioga Pass) — schematic netlist excerpt (pin names and nets, part order shuffled) for the footprints in the layout excerpt that follows; sources: Cadence DE-HDL packaged netlist, KiCad conversion of Wiwynn_Tioga_Pass_MB.brd

EU7F1  NCP3232L  IC  pkg SM  page 231
  SS  = VR_PVPP_ABC_SS
  FB  = VR_FB_PVPP_ABC
  COMP  = VR_COMP_PVPP_ABC_3
  ISET  = VR_PVPP_ABC_ISET
  AGND  = AGND_PVPP_ABC
  OTS  = AGND_PVPP_ABC
  PG  = PWRGD_PVPP_ABC_R
  VIN(0)  = VR_FET_SW_P12V_STBY_PVPP_ABC
  VIN(1)  = VR_FET_SW_P12V_STBY_PVPP_ABC
  VIN(2)  = VR_FET_SW_P12V_STBY_PVPP_ABC
  VIN(3)  = VR_FET_SW_P12V_STBY_PVPP_ABC
  VIN(4)  = VR_FET_SW_P12V_STBY_PVPP_ABC
  VIN(5)  = VR_FET_SW_P12V_STBY_PVPP_ABC
  VIN(6)  = VR_FET_SW_P12V_STBY_PVPP_ABC
  VSWH(0)  = VR_PVPP_ABC_PHASE
  PGND(0)  = GND
  PGND(1)  = GND
  PGND(2)  = GND
  PGND(3)  = GND
  PGND(4)  = GND
  PGND(5)  = GND
  PGND(6)  = GND
  PGND(7)  = GND
  PGND(8)  = GND
  PGND(9)  = GND
  PGND(10)  = GND
  PGND(11)  = GND
  PGND(12)  = GND
  VSWH(1)  = VR_PVPP_ABC_PHASE
  VSWH(2)  = VR_PVPP_ABC_PHASE
  VSWH(3)  = VR_PVPP_ABC_PHASE
  VSWH(4)  = VR_PVPP_ABC_PHASE
  VSWH(5)  = VR_PVPP_ABC_PHASE
  VSWH(6)  = VR_PVPP_ABC_PHASE
  VSW  = VR_PVPP_ABC_PHASE
  BST  = VR_PVPP_ABC_BOOT
  PGND(13)  = GND
  VB  = VR_VB_PVPP_ABC
  VCC  = VR_FET_SW_P12V_STBY_PVPP_ABC
  EN  = FM_PVPP_PVDDQ_CPU0_EN_ABC
  GND  = GND
  VIN(7)  = VR_FET_SW_P12V_STBY_PVPP_ABC
  VSWH(7)  = VR_PVPP_ABC_PHASE

(kicad_pcb
	(version 20260206)
	(generator "pcbnew")
	(generator_version "10.0")
	(general
		(thickness 1.6)
		(legacy_teardrops no)
	)
	(paper "A4")
	(title_block
		(title "Wiwynn_Tioga_Pass_MB.brd")
		(comment 1 "Tioga Pass / footprint 636 of 4770 (EU7F1), pads 36-43 of 43")
	)
	(layers
		(0 "F.Cu" signal "TOP")
		(4 "In1.Cu" signal "L2GND")
		(6 "In2.Cu" signal "L3")
		(8 "In3.Cu" signal "L4GND")
		(10 "In4.Cu" signal "L5")
		(12 "In5.Cu" signal "L6GND")
		(14 "In6.Cu" signal "L7VCC")
		(16 "In7.Cu" signal "L8VCC")
		(18 "In8.Cu" signal "L9GND")
		(20 "In9.Cu" signal "L10")
		(22 "In10.Cu" signal "L11GND")
		(24 "In11.Cu" signal "L12")
		(26 "In12.Cu" signal "L13GND")
		(2 "B.Cu" signal "BOTTOM")
		(9 "F.Adhes" user "F.Adhesive")
		(11 "B.Adhes" user "B.Adhesive")
		(13 "F.Paste" user "Package Geometry/Pastemask Top")
		(15 "B.Paste" user "Package Geometry/Pastemask Bottom")
		(5 "F.SilkS" user "Ref Des/Silkscreen Top")
		(7 "B.SilkS" user "Ref Des/Silkscreen Bottom")
		(1 "F.Mask" user "Board Geometry/Soldermask Top")
		(3 "B.Mask" user "Board Geometry/Soldermask Bottom")
		(17 "Dwgs.User" user "User.Drawings")
		(19 "Cmts.User" user "User.Comments")
		(21 "Eco1.User" user "User.Eco1")
		(23 "Eco2.User" user "User.Eco2")
		(25 "Edge.Cuts" user "Board Geometry/Outline")
		(27 "Margin" user)
		(31 "F.CrtYd" user "Package Geometry/Place Bound Top")
		(29 "B.CrtYd" user "Package Geometry/Place Bound Bottom")
		(35 "F.Fab" user "Ref Des/Assembly Top")
		(33 "B.Fab" user "Ref Des/Assembly Bottom")
	)
	(footprint ""
		(layer "F.Cu")
		(at 345.3638 -28.5623 90)
		(property "Reference" "EU7F1"
			(at 5.27939 -1.76022 0)
			(unlocked yes)
			(layer "F.SilkS")
			(effects
				(font
					(size 0.7874 0.5842)
					(thickness 0.1524)
				)
				(justify left)
			)
		)
		(property "Value" ""
			(at 0 0 90)
			(layer "F.Fab")
			(effects
				(font
					(size 1.27 1.27)
				)
			)
		)
		(duplicate_pad_numbers_are_jumpers no)
		(pad "36" smd custom
			(at -0.249936 -2.8321 90)
			(size 0.06985 0.06985)
			(layers "F.Cu" "F.Mask" "F.Paste")
			(net "VR_PVPP_ABC_BOOT")
			(options
				(clearance outline)
				(anchor circle)
			)
			(primitives
				(gr_poly
					(pts
						(arc
							(start 0.1397 0.2413)
							(mid 0 0.381)
							(end -0.1397 0.2413)
						)
						(xy -0.1397 -0.381) (xy 0.1397 -0.381)
					)
					(width 0)
					(fill yes)
				)
			)
		)
		(pad "37" smd custom
			(at -0.750062 -2.8321 90)
			(size 0.06985 0.06985)
			(layers "F.Cu" "F.Mask" "F.Paste")
			(net "GND")
			(options
				(clearance outline)
				(anchor circle)
			)
			(primitives
				(gr_poly
					(pts
						(arc
							(start 0.1397 0.2413)
							(mid 0 0.381)
							(end -0.1397 0.2413)
						)
						(xy -0.1397 -0.381) (xy 0.1397 -0.381)
					)
					(width 0)
					(fill yes)
				)
			)
		)
		(pad "38" smd custom
			(at -1.249934 -2.8321 90)
			(size 0.06985 0.06985)
			(layers "F.Cu" "F.Mask" "F.Paste")
			(net "VR_VB_PVPP_ABC")
			(options
				(clearance outline)
				(anchor circle)
			)
			(primitives
				(gr_poly
					(pts
						(arc
							(start 0.1397 0.2413)
							(mid 0 0.381)
							(end -0.1397 0.2413)
						)
						(xy -0.1397 -0.381) (xy 0.1397 -0.381)
					)
					(width 0)
					(fill yes)
				)
			)
		)
		(pad "39" smd custom
			(at -1.75006 -2.8321 90)
			(size 0.06985 0.06985)
			(layers "F.Cu" "F.Mask" "F.Paste")
			(net "VR_FET_SW_P12V_STBY_PVPP_ABC")
			(options
				(clearance outline)
				(anchor circle)
			)
			(primitives
				(gr_poly
					(pts
						(arc
							(start 0.1397 0.2413)
							(mid 0 0.381)
							(end -0.1397 0.2413)
						)
						(xy -0.1397 -0.381) (xy 0.1397 -0.381)
					)
					(width 0)
					(fill yes)
				)
			)
		)
		(pad "40" smd custom
			(at -2.249932 -2.8321 90)
			(size 0.06985 0.06985)
			(layers "F.Cu" "F.Mask" "F.Paste")
			(net "FM_PVPP_PVDDQ_CPU0_EN_ABC")
			(options
				(clearance outline)
				(anchor circle)
			)
			(primitives
				(gr_poly
					(pts
						(arc
							(start 0.1397 0.2413)
							(mid 0 0.381)
							(end -0.1397 0.2413)
						)
						(xy -0.1397 -0.381) (xy 0.1397 -0.381)
					)
					(width 0)
					(fill yes)
				)
			)
		)
		(pad "41" smd rect
			(at -1.4478 -1.1938 90)
			(size 1.4986 2.0066)
			(layers "F.Cu" "F.Mask" "F.Paste")
			(net "GND")
		)
		(pad "42" smd rect
			(at -1.4478 1.1938 90)
			(size 1.4986 2.0066)
			(layers "F.Cu" "F.Mask" "F.Paste")
			(net "VR_FET_SW_P12V_STBY_PVPP_ABC")
		)
		(pad "43" smd rect
			(at 1.0033 0 90)
			(size 2.3876 4.3942)
			(layers "F.Cu" "F.Mask" "F.Paste")
			(net "VR_PVPP_ABC_PHASE")
		)
	)
)
